# S9S_MB_2U (Grand Teton) — schematic netlist excerpt (pin names and nets, part order shuffled) for the footprints in the layout excerpt that follows; sources: Cadence DE-HDL packaged netlist, KiCad conversion of 03242023_DA0F0TMBIJ0_F0T_Motherboard_J_brd_V01_OCP.brd

R3110  Q_RES  0 5% CHIP  pkg 0402LF  page 234 : A = SMB_1_BMC_GPU_SDA ; B = SMB_1_BMC_GPU_R_SDA
C233  Q_CAP  10UF 6.3V 20% X6S  pkg C0402  page 77 : A = PVCCIN_CPU1 ; B = GND

(kicad_pcb
	(version 20260206)
	(generator "pcbnew")
	(generator_version "10.0")
	(general
		(thickness 1.6)
		(legacy_teardrops no)
	)
	(paper "A4")
	(title_block
		(title "03242023_DA0F0TMBIJ0_F0T_Motherboard_J_brd_V01_OCP.brd")
		(comment 1 "Grand Teton / footprints 2508-2509 of 6105")
	)
	(layers
		(0 "F.Cu" signal "TOP")
		(4 "In1.Cu" signal "GND")
		(6 "In2.Cu" signal "IN1")
		(8 "In3.Cu" signal "GND1")
		(10 "In4.Cu" signal "IN2")
		(12 "In5.Cu" signal "GND2")
		(14 "In6.Cu" signal "IN3")
		(16 "In7.Cu" signal "GND3")
		(18 "In8.Cu" signal "VCC")
		(20 "In9.Cu" signal "VCC1")
		(22 "In10.Cu" signal "GND4")
		(24 "In11.Cu" signal "IN4")
		(26 "In12.Cu" signal "GND5")
		(28 "In13.Cu" signal "IN5")
		(30 "In14.Cu" signal "GND6")
		(32 "In15.Cu" signal "IN6")
		(34 "In16.Cu" signal "GND7")
		(2 "B.Cu" signal "BOTTOM")
		(9 "F.Adhes" user "F.Adhesive")
		(11 "B.Adhes" user "B.Adhesive")
		(13 "F.Paste" user "Package Geometry/Pastemask Top")
		(15 "B.Paste" user "Package Geometry/Pastemask Bottom")
		(5 "F.SilkS" user "Ref Des/Silkscreen Top")
		(7 "B.SilkS" user "Ref Des/Silkscreen Bottom")
		(1 "F.Mask" user "Board Geometry/Soldermask Top")
		(3 "B.Mask" user "Board Geometry/Soldermask Bottom")
		(17 "Dwgs.User" user "User.Drawings")
		(19 "Cmts.User" user "User.Comments")
		(21 "Eco1.User" user "User.Eco1")
		(23 "Eco2.User" user "User.Eco2")
		(25 "Edge.Cuts" user "Board Geometry/Outline")
		(27 "Margin" user)
		(31 "F.CrtYd" user "Package Geometry/Place Bound Top")
		(29 "B.CrtYd" user "Package Geometry/Place Bound Bottom")
		(35 "F.Fab" user "Ref Des/Assembly Top")
		(33 "B.Fab" user "Ref Des/Assembly Bottom")
	)
	(footprint ""
		(layer "F.Cu")
		(at 52.50688 -434.304948 180)
		(property "Reference" "R3110"
			(at 0 0 180)
			(layer "F.SilkS")
			(hide yes)
			(effects
				(font
					(size 1.27 1.27)
				)
			)
		)
		(property "Value" ""
			(at 0 0 180)
			(layer "F.Fab")
			(effects
				(font
					(size 1.27 1.27)
				)
			)
		)
		(duplicate_pad_numbers_are_jumpers no)
		(fp_line
			(start 0.7874 0.4064)
			(end -0.7874 0.4064)
			(stroke
				(width 0.1524)
				(type default)
			)
			(layer "F.SilkS")
		)
		(fp_line
			(start 0.7874 -0.4064)
			(end 0.7874 0.4064)
			(stroke
				(width 0.1524)
				(type default)
			)
			(layer "F.SilkS")
		)
		(fp_line
			(start -0.7874 0.4064)
			(end -0.7874 -0.4064)
			(stroke
				(width 0.1524)
				(type default)
			)
			(layer "F.SilkS")
		)
		(fp_line
			(start -0.7874 -0.4064)
			(end 0.7874 -0.4064)
			(stroke
				(width 0.1524)
				(type default)
			)
			(layer "F.SilkS")
		)
		(fp_line
			(start 0.67945 0.3048)
			(end 0.120396 0.3048)
			(stroke
				(width 0.1)
				(type default)
			)
			(layer "F.Fab")
		)
		(fp_line
			(start 0.67945 -0.3048)
			(end 0.67945 0.3048)
			(stroke
				(width 0.1)
				(type default)
			)
			(layer "F.Fab")
		)
		(fp_line
			(start 0.12065 -0.2794)
			(end 0.12065 -0.3048)
			(stroke
				(width 0.1)
				(type default)
			)
			(layer "F.Fab")
		)
		(fp_line
			(start 0.12065 -0.3048)
			(end 0.67945 -0.3048)
			(stroke
				(width 0.1)
				(type default)
			)
			(layer "F.Fab")
		)
		(fp_line
			(start 0.120396 0.3048)
			(end 0.120396 0.2794)
			(stroke
				(width 0.1)
				(type default)
			)
			(layer "F.Fab")
		)
		(fp_line
			(start 0.120396 0.2794)
			(end -0.12065 0.2794)
			(stroke
				(width 0.1)
				(type default)
			)
			(layer "F.Fab")
		)
		(fp_line
			(start -0.12065 0.3048)
			(end -0.67945 0.3048)
			(stroke
				(width 0.1)
				(type default)
			)
			(layer "F.Fab")
		)
		(fp_line
			(start -0.12065 0.2794)
			(end -0.12065 0.3048)
			(stroke
				(width 0.1)
				(type default)
			)
			(layer "F.Fab")
		)
		(fp_line
			(start -0.12065 -0.2794)
			(end 0.12065 -0.2794)
			(stroke
				(width 0.1)
				(type default)
			)
			(layer "F.Fab")
		)
		(fp_line
			(start -0.12065 -0.305054)
			(end -0.12065 -0.2794)
			(stroke
				(width 0.1)
				(type default)
			)
			(layer "F.Fab")
		)
		(fp_line
			(start -0.67945 0.3048)
			(end -0.67945 -0.305054)
			(stroke
				(width 0.1)
				(type default)
			)
			(layer "F.Fab")
		)
		(fp_line
			(start -0.67945 -0.305054)
			(end -0.12065 -0.305054)
			(stroke
				(width 0.1)
				(type default)
			)
			(layer "F.Fab")
		)
		(pad "1" smd circle
			(at -0.40005 0 180)
			(size 0 0)
			(layers "F.Cu" "F.Mask" "F.Paste")
			(net "SMB_1_BMC_GPU_SDA")
		)
		(pad "2" smd circle
			(at 0.40005 0 180)
			(size 0 0)
			(layers "F.Cu" "F.Mask" "F.Paste")
			(net "SMB_1_BMC_GPU_R_SDA")
		)
	)
	(footprint ""
		(layer "F.Cu")
		(at 119.508016 -258.72694 90)
		(property "Reference" "C233"
			(at 0 0 90)
			(layer "F.SilkS")
			(hide yes)
			(effects
				(font
					(size 1.27 1.27)
				)
			)
		)
		(property "Value" ""
			(at 0 0 90)
			(layer "F.Fab")
			(effects
				(font
					(size 1.27 1.27)
				)
			)
		)
		(duplicate_pad_numbers_are_jumpers no)
		(fp_line
			(start 0.7874 -0.4064)
			(end 0.7874 0.4064)
			(stroke
				(width 0.1524)
				(type default)
			)
			(layer "F.SilkS")
		)
		(fp_line
			(start -0.7874 -0.4064)
			(end 0.7874 -0.4064)
			(stroke
				(width 0.1524)
				(type default)
			)
			(layer "F.SilkS")
		)
		(fp_line
			(start 0.7874 0.4064)
			(end -0.7874 0.4064)
			(stroke
				(width 0.1524)
				(type default)
			)
			(layer "F.SilkS")
		)
		(fp_line
			(start -0.7874 0.4064)
			(end -0.7874 -0.4064)
			(stroke
				(width 0.1524)
				(type default)
			)
			(layer "F.SilkS")
		)
		(fp_line
			(start -0.12065 -0.305054)
			(end -0.12065 -0.2794)
			(stroke
				(width 0.1)
				(type default)
			)
			(layer "F.Fab")
		)
		(fp_line
			(start -0.67945 -0.305054)
			(end -0.12065 -0.305054)
			(stroke
				(width 0.1)
				(type default)
			)
			(layer "F.Fab")
		)
		(fp_line
			(start 0.67945 -0.3048)
			(end 0.67945 0.3048)
			(stroke
				(width 0.1)
				(type default)
			)
			(layer "F.Fab")
		)
		(fp_line
			(start 0.12065 -0.3048)
			(end 0.67945 -0.3048)
			(stroke
				(width 0.1)
				(type default)
			)
			(layer "F.Fab")
		)
		(fp_line
			(start 0.12065 -0.2794)
			(end 0.12065 -0.3048)
			(stroke
				(width 0.1)
				(type default)
			)
			(layer "F.Fab")
		)
		(fp_line
			(start -0.12065 -0.2794)
			(end 0.12065 -0.2794)
			(stroke
				(width 0.1)
				(type default)
			)
			(layer "F.Fab")
		)
		(fp_line
			(start 0.120396 0.2794)
			(end -0.12065 0.2794)
			(stroke
				(width 0.1)
				(type default)
			)
			(layer "F.Fab")
		)
		(fp_line
			(start -0.12065 0.2794)
			(end -0.12065 0.3048)
			(stroke
				(width 0.1)
				(type default)
			)
			(layer "F.Fab")
		)
		(fp_line
			(start 0.67945 0.3048)
			(end 0.120396 0.3048)
			(stroke
				(width 0.1)
				(type default)
			)
			(layer "F.Fab")
		)
		(fp_line
			(start 0.120396 0.3048)
			(end 0.120396 0.2794)
			(stroke
				(width 0.1)
				(type default)
			)
			(layer "F.Fab")
		)
		(fp_line
			(start -0.12065 0.3048)
			(end -0.67945 0.3048)
			(stroke
				(width 0.1)
				(type default)
			)
			(layer "F.Fab")
		)
		(fp_line
			(start -0.67945 0.3048)
			(end -0.67945 -0.305054)
			(stroke
				(width 0.1)
				(type default)
			)
			(layer "F.Fab")
		)
		(pad "1" smd circle
			(at -0.40005 0 90)
			(size 0 0)
			(layers "F.Cu" "F.Mask" "F.Paste")
			(net "PVCCIN_CPU1")
		)
		(pad "2" smd circle
			(at 0.40005 0 90)
			(size 0 0)
			(layers "F.Cu" "F.Mask" "F.Paste")
			(net "GND")
		)
	)
)
